# T6G (Grand Teton) — schematic netlist excerpt (pin names and nets, part order shuffled) for the footprints in the layout excerpt that follows; sources: Cadence DE-HDL packaged netlist, KiCad conversion of 04192023_DAF0TMB3IC0_F0TG_MB_C_brd_V02_OCP.brd

J109  CONN112_10137002101LF  CONN112_10137002-101LF IO  pkg HSD_F112D8_P2W1-2_RDH  page 119
  A1  = BMC_MONITER_BUF
  A2  = GND
  A3  = BIC_MONITER
  A4  = GND
  A5  = SMB_BMC_SWB_BUF_SCL
  A6  = GND
  A7  = SMB_BMC_SWB_BUF_SDA
  A8  = GND
  B1  = GND
  B2  = P5E_CPU1_P2_RX_BUF_DN<9>
  B3  = GND
  B4  = P5E_CPU1_P2_RX_BUF_DN<11>
  B5  = GND
  B6  = P5E_CPU1_P2_RX_BUF_DN<13>
  B7  = GND
  B8  = P5E_CPU1_P2_RX_BUF_DN<15>
  C1  = P5E_CPU1_P2_RX_BUF_DN<8>
  C2  = P5E_CPU1_P2_RX_BUF_DP<9>
  C3  = P5E_CPU1_P2_RX_BUF_DN<10>
  C4  = P5E_CPU1_P2_RX_BUF_DP<11>
  C5  = P5E_CPU1_P2_RX_BUF_DN<12>
  C6  = P5E_CPU1_P2_RX_BUF_DP<13>
  C7  = P5E_CPU1_P2_RX_BUF_DN<14>
  C8  = P5E_CPU1_P2_RX_BUF_DP<15>
  D1  = P5E_CPU1_P2_RX_BUF_DP<8>
  D2  = GND
  D3  = P5E_CPU1_P2_RX_BUF_DP<10>
  D4  = GND
  D5  = P5E_CPU1_P2_RX_BUF_DP<12>
  D6  = GND
  D7  = P5E_CPU1_P2_RX_BUF_DP<14>
  D8  = GND
  E1  = GND
  E2  = P5E_CPU1_P3_RX_BUF_DN<9>
  E3  = GND
  E4  = P5E_CPU1_P3_RX_BUF_DN<11>
  E5  = GND
  E6  = P5E_CPU1_P3_RX_BUF_DN<13>
  E7  = GND
  E8  = P5E_CPU1_P3_RX_BUF_DN<15>
  F1  = P5E_CPU1_P3_RX_BUF_DN<8>
  F2  = P5E_CPU1_P3_RX_BUF_DP<9>
  F3  = P5E_CPU1_P3_RX_BUF_DN<10>
  F4  = P5E_CPU1_P3_RX_BUF_DP<11>
  F5  = P5E_CPU1_P3_RX_BUF_DN<12>
  F6  = P5E_CPU1_P3_RX_BUF_DP<13>
  F7  = P5E_CPU1_P3_RX_BUF_DN<14>
  F8  = P5E_CPU1_P3_RX_BUF_DP<15>
  G1  = P5E_CPU1_P3_RX_BUF_DP<8>
  G2  = GND
  G3  = P5E_CPU1_P3_RX_BUF_DP<10>
  G4  = GND
  G5  = P5E_CPU1_P3_RX_BUF_DP<12>
  G6  = GND
  G7  = P5E_CPU1_P3_RX_BUF_DP<14>
  G8  = GND
  H1  = GND
  H2  = P5E_CPU1_P2_TX_BUF_C_DN<9>
  H3  = GND
  H4  = P5E_CPU1_P2_TX_BUF_C_DN<11>
  H5  = GND
  H6  = P5E_CPU1_P2_TX_BUF_C_DN<13>
  H7  = GND
  H8  = P5E_CPU1_P2_TX_BUF_C_DN<15>
  I1  = P5E_CPU1_P2_TX_BUF_C_DN<8>
  I2  = P5E_CPU1_P2_TX_BUF_C_DP<9>
  I3  = P5E_CPU1_P2_TX_BUF_C_DN<10>
  I4  = P5E_CPU1_P2_TX_BUF_C_DP<11>
  I5  = P5E_CPU1_P2_TX_BUF_C_DN<12>
  I6  = P5E_CPU1_P2_TX_BUF_C_DP<13>
  I7  = P5E_CPU1_P2_TX_BUF_C_DN<14>
  I8  = P5E_CPU1_P2_TX_BUF_C_DP<15>
  J1  = P5E_CPU1_P2_TX_BUF_C_DP<8>
  J2  = GND
  J3  = P5E_CPU1_P2_TX_BUF_C_DP<10>
  J4  = GND
  J5  = P5E_CPU1_P2_TX_BUF_C_DP<12>
  J6  = GND
  J7  = P5E_CPU1_P2_TX_BUF_C_DP<14>
  J8  = GND
  K1  = GND
  K2  = P5E_CPU1_P3_TX_BUF_C_DN<9>
  K3  = GND
  K4  = P5E_CPU1_P3_TX_BUF_C_DN<11>
  K5  = GND
  K6  = P5E_CPU1_P3_TX_BUF_C_DN<13>
  K7  = GND
  K8  = P5E_CPU1_P3_TX_BUF_C_DN<15>
  L1  = P5E_CPU1_P3_TX_BUF_C_DN<8>
  L2  = P5E_CPU1_P3_TX_BUF_C_DP<9>
  L3  = P5E_CPU1_P3_TX_BUF_C_DN<10>
  L4  = P5E_CPU1_P3_TX_BUF_C_DP<11>
  L5  = P5E_CPU1_P3_TX_BUF_C_DN<12>
  L6  = P5E_CPU1_P3_TX_BUF_C_DP<13>
  L7  = P5E_CPU1_P3_TX_BUF_C_DN<14>
  L8  = P5E_CPU1_P3_TX_BUF_C_DP<15>
  M1  = P5E_CPU1_P3_TX_BUF_C_DP<8>
  M2  = GND
  M3  = P5E_CPU1_P3_TX_BUF_C_DP<10>
  M4  = GND
  M5  = P5E_CPU1_P3_TX_BUF_C_DP<12>
  M6  = GND
  M7  = P5E_CPU1_P3_TX_BUF_C_DP<14>
  M8  = GND
  N1  = GND
  N2  = GPU_FPGA_EROT_FATALERR_N
  N3  = GND
  N4  = GPU_3V3IO_RSVD0_FFU
  N5  = GND
  N6  = GPU_3V3IO_RSVD1_FFU
  N7  = GND
  N8  = PRSNT_CABLE_GPU_B3_N

(kicad_pcb
	(version 20260206)
	(generator "pcbnew")
	(generator_version "10.0")
	(general
		(thickness 1.6)
		(legacy_teardrops no)
	)
	(paper "A4")
	(title_block
		(title "04192023_DAF0TMB3IC0_F0TG_MB_C_brd_V02_OCP.brd")
		(comment 1 "Grand Teton / footprint 1153 of 8354 (J109), pads 1-31 of 48")
	)
	(layers
		(0 "F.Cu" signal "TOP")
		(4 "In1.Cu" signal "GND")
		(6 "In2.Cu" signal "IN1")
		(8 "In3.Cu" signal "GND1")
		(10 "In4.Cu" signal "IN2")
		(12 "In5.Cu" signal "GND2")
		(14 "In6.Cu" signal "IN3")
		(16 "In7.Cu" signal "GND3")
		(18 "In8.Cu" signal "VCC")
		(20 "In9.Cu" signal "VCC1")
		(22 "In10.Cu" signal "GND4")
		(24 "In11.Cu" signal "IN4")
		(26 "In12.Cu" signal "GND5")
		(28 "In13.Cu" signal "IN5")
		(30 "In14.Cu" signal "GND6")
		(32 "In15.Cu" signal "IN6")
		(34 "In16.Cu" signal "GND7")
		(2 "B.Cu" signal "BOTTOM")
		(9 "F.Adhes" user "F.Adhesive")
		(11 "B.Adhes" user "B.Adhesive")
		(13 "F.Paste" user "Package Geometry/Pastemask Top")
		(15 "B.Paste" user "Package Geometry/Pastemask Bottom")
		(5 "F.SilkS" user "Ref Des/Silkscreen Top")
		(7 "B.SilkS" user "Ref Des/Silkscreen Bottom")
		(1 "F.Mask" user "Board Geometry/Soldermask Top")
		(3 "B.Mask" user "Board Geometry/Soldermask Bottom")
		(17 "Dwgs.User" user "User.Drawings")
		(19 "Cmts.User" user "User.Comments")
		(21 "Eco1.User" user "User.Eco1")
		(23 "Eco2.User" user "User.Eco2")
		(25 "Edge.Cuts" user "Board Geometry/Outline")
		(27 "Margin" user)
		(31 "F.CrtYd" user "Package Geometry/Place Bound Top")
		(29 "B.CrtYd" user "Package Geometry/Place Bound Bottom")
		(35 "F.Fab" user "Ref Des/Assembly Top")
		(33 "B.Fab" user "Ref Des/Assembly Bottom")
	)
	(footprint ""
		(layer "F.Cu")
		(at 142.750032 -440.489848)
		(property "Reference" "J109"
			(at 17.580102 23.22576 0)
			(unlocked yes)
			(layer "F.SilkS")
			(effects
				(font
					(size 0.7874 0.5842)
					(thickness 0.1524)
				)
				(justify left)
			)
		)
		(property "Value" ""
			(at 0 0 0)
			(layer "F.Fab")
			(effects
				(font
					(size 1.27 1.27)
				)
			)
		)
		(duplicate_pad_numbers_are_jumpers no)
		(pad "A1" thru_hole rect
			(at 0 0 180)
			(size 0.766318 0.766318)
			(drill 0.359918)
			(layers "*.Cu" "*.Mask")
			(remove_unused_layers no)
			(net "BMC_MONITER_BUF")
			(clearance 0.0508)
			(thermal_gap 0.0508)
			(padstack
				(mode front_inner_back)
				(layer "Inner"
					(shape circle)
					(size 0.766318 0.766318)
					(clearance 0.0508)
				)
				(layer "B.Cu"
					(shape rect)
					(size 0.766318 0.766318)
					(clearance 0.0508)
				)
			)
		)
		(pad "A2" thru_hole circle
			(at 1.999996 0.199898 180)
			(size 0.906272 0.906272)
			(drill 0.499872)
			(layers "*.Cu" "*.Mask")
			(remove_unused_layers no)
			(net "GND")
			(clearance 0.0508)
			(thermal_gap 0.0508)
		)
		(pad "A3" thru_hole circle
			(at 3.999992 0 180)
			(size 0.766318 0.766318)
			(drill 0.359918)
			(layers "*.Cu" "*.Mask")
			(remove_unused_layers no)
			(net "BIC_MONITER")
			(clearance 0.0508)
			(thermal_gap 0.0508)
		)
		(pad "A4" thru_hole circle
			(at 5.999988 0.199898 180)
			(size 0.906272 0.906272)
			(drill 0.499872)
			(layers "*.Cu" "*.Mask")
			(remove_unused_layers no)
			(net "GND")
			(clearance 0.0508)
			(thermal_gap 0.0508)
		)
		(pad "A5" thru_hole circle
			(at 7.999984 0 180)
			(size 0.766318 0.766318)
			(drill 0.359918)
			(layers "*.Cu" "*.Mask")
			(remove_unused_layers no)
			(net "SMB_BMC_SWB_BUF_SCL")
			(clearance 0.0508)
			(thermal_gap 0.0508)
		)
		(pad "A6" thru_hole circle
			(at 9.99998 0.199898 180)
			(size 0.906272 0.906272)
			(drill 0.499872)
			(layers "*.Cu" "*.Mask")
			(remove_unused_layers no)
			(net "GND")
			(clearance 0.0508)
			(thermal_gap 0.0508)
		)
		(pad "A7" thru_hole circle
			(at 11.999976 0 180)
			(size 0.766318 0.766318)
			(drill 0.359918)
			(layers "*.Cu" "*.Mask")
			(remove_unused_layers no)
			(net "SMB_BMC_SWB_BUF_SDA")
			(clearance 0.0508)
			(thermal_gap 0.0508)
		)
		(pad "A8" thru_hole circle
			(at 13.999972 0.199898 180)
			(size 0.906272 0.906272)
			(drill 0.499872)
			(layers "*.Cu" "*.Mask")
			(remove_unused_layers no)
			(net "GND")
			(clearance 0.0508)
			(thermal_gap 0.0508)
		)
		(pad "B1" thru_hole circle
			(at 0 1.199896 180)
			(size 0.906272 0.906272)
			(drill 0.499872)
			(layers "*.Cu" "*.Mask")
			(remove_unused_layers no)
			(net "GND")
			(clearance 0.0508)
			(thermal_gap 0.0508)
		)
		(pad "B3" thru_hole circle
			(at 3.999992 1.199896 180)
			(size 0.906272 0.906272)
			(drill 0.499872)
			(layers "*.Cu" "*.Mask")
			(remove_unused_layers no)
			(net "GND")
			(clearance 0.0508)
			(thermal_gap 0.0508)
		)
		(pad "B5" thru_hole circle
			(at 7.999984 1.199896 180)
			(size 0.906272 0.906272)
			(drill 0.499872)
			(layers "*.Cu" "*.Mask")
			(remove_unused_layers no)
			(net "GND")
			(clearance 0.0508)
			(thermal_gap 0.0508)
		)
		(pad "B7" thru_hole circle
			(at 11.999976 1.199896 180)
			(size 0.906272 0.906272)
			(drill 0.499872)
			(layers "*.Cu" "*.Mask")
			(remove_unused_layers no)
			(net "GND")
			(clearance 0.0508)
			(thermal_gap 0.0508)
		)
		(pad "D2" thru_hole circle
			(at 1.999996 3.800094 180)
			(size 0.906272 0.906272)
			(drill 0.499872)
			(layers "*.Cu" "*.Mask")
			(remove_unused_layers no)
			(net "GND")
			(clearance 0.0508)
			(thermal_gap 0.0508)
		)
		(pad "D4" thru_hole circle
			(at 5.999988 3.800094 180)
			(size 0.906272 0.906272)
			(drill 0.499872)
			(layers "*.Cu" "*.Mask")
			(remove_unused_layers no)
			(net "GND")
			(clearance 0.0508)
			(thermal_gap 0.0508)
		)
		(pad "D6" thru_hole circle
			(at 9.99998 3.800094 180)
			(size 0.906272 0.906272)
			(drill 0.499872)
			(layers "*.Cu" "*.Mask")
			(remove_unused_layers no)
			(net "GND")
			(clearance 0.0508)
			(thermal_gap 0.0508)
		)
		(pad "D8" thru_hole circle
			(at 13.999972 3.800094 180)
			(size 0.906272 0.906272)
			(drill 0.499872)
			(layers "*.Cu" "*.Mask")
			(remove_unused_layers no)
			(net "GND")
			(clearance 0.0508)
			(thermal_gap 0.0508)
		)
		(pad "E1" thru_hole circle
			(at 0 4.800092 180)
			(size 0.906272 0.906272)
			(drill 0.499872)
			(layers "*.Cu" "*.Mask")
			(remove_unused_layers no)
			(net "GND")
			(clearance 0.0508)
			(thermal_gap 0.0508)
		)
		(pad "E3" thru_hole circle
			(at 3.999992 4.800092 180)
			(size 0.906272 0.906272)
			(drill 0.499872)
			(layers "*.Cu" "*.Mask")
			(remove_unused_layers no)
			(net "GND")
			(clearance 0.0508)
			(thermal_gap 0.0508)
		)
		(pad "E5" thru_hole circle
			(at 7.999984 4.800092 180)
			(size 0.906272 0.906272)
			(drill 0.499872)
			(layers "*.Cu" "*.Mask")
			(remove_unused_layers no)
			(net "GND")
			(clearance 0.0508)
			(thermal_gap 0.0508)
		)
		(pad "E7" thru_hole circle
			(at 11.999976 4.800092 180)
			(size 0.906272 0.906272)
			(drill 0.499872)
			(layers "*.Cu" "*.Mask")
			(remove_unused_layers no)
			(net "GND")
			(clearance 0.0508)
			(thermal_gap 0.0508)
		)
		(pad "G2" thru_hole circle
			(at 1.999996 7.400036 180)
			(size 0.906272 0.906272)
			(drill 0.499872)
			(layers "*.Cu" "*.Mask")
			(remove_unused_layers no)
			(net "GND")
			(clearance 0.0508)
			(thermal_gap 0.0508)
		)
		(pad "G4" thru_hole circle
			(at 5.999988 7.400036 180)
			(size 0.906272 0.906272)
			(drill 0.499872)
			(layers "*.Cu" "*.Mask")
			(remove_unused_layers no)
			(net "GND")
			(clearance 0.0508)
			(thermal_gap 0.0508)
		)
		(pad "G6" thru_hole circle
			(at 9.99998 7.400036 180)
			(size 0.906272 0.906272)
			(drill 0.499872)
			(layers "*.Cu" "*.Mask")
			(remove_unused_layers no)
			(net "GND")
			(clearance 0.0508)
			(thermal_gap 0.0508)
		)
		(pad "G8" thru_hole circle
			(at 13.999972 7.400036 180)
			(size 0.906272 0.906272)
			(drill 0.499872)
			(layers "*.Cu" "*.Mask")
			(remove_unused_layers no)
			(net "GND")
			(clearance 0.0508)
			(thermal_gap 0.0508)
		)
		(pad "H1" thru_hole circle
			(at 0 8.400034 180)
			(size 0.906272 0.906272)
			(drill 0.499872)
			(layers "*.Cu" "*.Mask")
			(remove_unused_layers no)
			(net "GND")
			(clearance 0.0508)
			(thermal_gap 0.0508)
		)
		(pad "H3" thru_hole circle
			(at 3.999992 8.400034 180)
			(size 0.906272 0.906272)
			(drill 0.499872)
			(layers "*.Cu" "*.Mask")
			(remove_unused_layers no)
			(net "GND")
			(clearance 0.0508)
			(thermal_gap 0.0508)
		)
		(pad "H5" thru_hole circle
			(at 7.999984 8.400034 180)
			(size 0.906272 0.906272)
			(drill 0.499872)
			(layers "*.Cu" "*.Mask")
			(remove_unused_layers no)
			(net "GND")
			(clearance 0.0508)
			(thermal_gap 0.0508)
		)
		(pad "H7" thru_hole circle
			(at 11.999976 8.400034 180)
			(size 0.906272 0.906272)
			(drill 0.499872)
			(layers "*.Cu" "*.Mask")
			(remove_unused_layers no)
			(net "GND")
			(clearance 0.0508)
			(thermal_gap 0.0508)
		)
		(pad "J2" thru_hole circle
			(at 1.999996 10.999978 180)
			(size 0.906272 0.906272)
			(drill 0.499872)
			(layers "*.Cu" "*.Mask")
			(remove_unused_layers no)
			(net "GND")
			(clearance 0.0508)
			(thermal_gap 0.0508)
		)
		(pad "J4" thru_hole circle
			(at 5.999988 10.999978 180)
			(size 0.906272 0.906272)
			(drill 0.499872)
			(layers "*.Cu" "*.Mask")
			(remove_unused_layers no)
			(net "GND")
			(clearance 0.0508)
			(thermal_gap 0.0508)
		)
		(pad "J6" thru_hole circle
			(at 9.99998 10.999978 180)
			(size 0.906272 0.906272)
			(drill 0.499872)
			(layers "*.Cu" "*.Mask")
			(remove_unused_layers no)
			(net "GND")
			(clearance 0.0508)
			(thermal_gap 0.0508)
		)
	)
)
